# T6G (Grand Teton) — schematic netlist excerpt (pin names and nets, part order shuffled) for the footprints in the layout excerpt that follows; sources: Cadence DE-HDL packaged netlist, KiCad conversion of 04192023_DAF0TMB3IC0_F0TG_MB_C_brd_V02_OCP.brd

R1658  Q_RES  4.7K 5% CHIP  pkg 0402LF  page 171 : A = SCM_JTAG_MUX_S0 ; B = GND
PC237  Q_CAP  1UF 25V 10% X6S  pkg C0402  page 209 : A = SW_P12V_AUX_PVDD18_S5_P0_FLT ; B = GND

(kicad_pcb
	(version 20260206)
	(generator "pcbnew")
	(generator_version "10.0")
	(general
		(thickness 1.6)
		(legacy_teardrops no)
	)
	(paper "A4")
	(title_block
		(title "04192023_DAF0TMB3IC0_F0TG_MB_C_brd_V02_OCP.brd")
		(comment 1 "Grand Teton / footprints 4654-4655 of 8354")
	)
	(layers
		(0 "F.Cu" signal "TOP")
		(4 "In1.Cu" signal "GND")
		(6 "In2.Cu" signal "IN1")
		(8 "In3.Cu" signal "GND1")
		(10 "In4.Cu" signal "IN2")
		(12 "In5.Cu" signal "GND2")
		(14 "In6.Cu" signal "IN3")
		(16 "In7.Cu" signal "GND3")
		(18 "In8.Cu" signal "VCC")
		(20 "In9.Cu" signal "VCC1")
		(22 "In10.Cu" signal "GND4")
		(24 "In11.Cu" signal "IN4")
		(26 "In12.Cu" signal "GND5")
		(28 "In13.Cu" signal "IN5")
		(30 "In14.Cu" signal "GND6")
		(32 "In15.Cu" signal "IN6")
		(34 "In16.Cu" signal "GND7")
		(2 "B.Cu" signal "BOTTOM")
		(9 "F.Adhes" user "F.Adhesive")
		(11 "B.Adhes" user "B.Adhesive")
		(13 "F.Paste" user "Package Geometry/Pastemask Top")
		(15 "B.Paste" user "Package Geometry/Pastemask Bottom")
		(5 "F.SilkS" user "Ref Des/Silkscreen Top")
		(7 "B.SilkS" user "Ref Des/Silkscreen Bottom")
		(1 "F.Mask" user "Board Geometry/Soldermask Top")
		(3 "B.Mask" user "Board Geometry/Soldermask Bottom")
		(17 "Dwgs.User" user "User.Drawings")
		(19 "Cmts.User" user "User.Comments")
		(21 "Eco1.User" user "User.Eco1")
		(23 "Eco2.User" user "User.Eco2")
		(25 "Edge.Cuts" user "Board Geometry/Outline")
		(27 "Margin" user)
		(31 "F.CrtYd" user "Package Geometry/Place Bound Top")
		(29 "B.CrtYd" user "Package Geometry/Place Bound Bottom")
		(35 "F.Fab" user "Ref Des/Assembly Top")
		(33 "B.Fab" user "Ref Des/Assembly Bottom")
	)
	(footprint ""
		(layer "F.Cu")
		(at 138.426952 -56.500014 180)
		(property "Reference" "R1658"
			(at 0 0 180)
			(layer "F.SilkS")
			(hide yes)
			(effects
				(font
					(size 1.27 1.27)
				)
			)
		)
		(property "Value" ""
			(at 0 0 180)
			(layer "F.Fab")
			(effects
				(font
					(size 1.27 1.27)
				)
			)
		)
		(duplicate_pad_numbers_are_jumpers no)
		(fp_line
			(start 0.7874 0.4064)
			(end -0.7874 0.4064)
			(stroke
				(width 0.1524)
				(type default)
			)
			(layer "F.SilkS")
		)
		(fp_line
			(start 0.7874 -0.4064)
			(end 0.7874 0.4064)
			(stroke
				(width 0.1524)
				(type default)
			)
			(layer "F.SilkS")
		)
		(fp_line
			(start -0.7874 0.4064)
			(end -0.7874 -0.4064)
			(stroke
				(width 0.1524)
				(type default)
			)
			(layer "F.SilkS")
		)
		(fp_line
			(start -0.7874 -0.4064)
			(end 0.7874 -0.4064)
			(stroke
				(width 0.1524)
				(type default)
			)
			(layer "F.SilkS")
		)
		(fp_line
			(start 0.67945 0.3048)
			(end 0.120396 0.3048)
			(stroke
				(width 0.1)
				(type default)
			)
			(layer "F.Fab")
		)
		(fp_line
			(start 0.67945 -0.3048)
			(end 0.67945 0.3048)
			(stroke
				(width 0.1)
				(type default)
			)
			(layer "F.Fab")
		)
		(fp_line
			(start 0.12065 -0.2794)
			(end 0.12065 -0.3048)
			(stroke
				(width 0.1)
				(type default)
			)
			(layer "F.Fab")
		)
		(fp_line
			(start 0.12065 -0.3048)
			(end 0.67945 -0.3048)
			(stroke
				(width 0.1)
				(type default)
			)
			(layer "F.Fab")
		)
		(fp_line
			(start 0.120396 0.3048)
			(end 0.120396 0.2794)
			(stroke
				(width 0.1)
				(type default)
			)
			(layer "F.Fab")
		)
		(fp_line
			(start 0.120396 0.2794)
			(end -0.12065 0.2794)
			(stroke
				(width 0.1)
				(type default)
			)
			(layer "F.Fab")
		)
		(fp_line
			(start -0.12065 0.3048)
			(end -0.67945 0.3048)
			(stroke
				(width 0.1)
				(type default)
			)
			(layer "F.Fab")
		)
		(fp_line
			(start -0.12065 0.2794)
			(end -0.12065 0.3048)
			(stroke
				(width 0.1)
				(type default)
			)
			(layer "F.Fab")
		)
		(fp_line
			(start -0.12065 -0.2794)
			(end 0.12065 -0.2794)
			(stroke
				(width 0.1)
				(type default)
			)
			(layer "F.Fab")
		)
		(fp_line
			(start -0.12065 -0.305054)
			(end -0.12065 -0.2794)
			(stroke
				(width 0.1)
				(type default)
			)
			(layer "F.Fab")
		)
		(fp_line
			(start -0.67945 0.3048)
			(end -0.67945 -0.305054)
			(stroke
				(width 0.1)
				(type default)
			)
			(layer "F.Fab")
		)
		(fp_line
			(start -0.67945 -0.305054)
			(end -0.12065 -0.305054)
			(stroke
				(width 0.1)
				(type default)
			)
			(layer "F.Fab")
		)
		(pad "1" smd circle
			(at -0.40005 0 180)
			(size 0 0)
			(layers "F.Cu" "F.Mask" "F.Paste")
			(net "SCM_JTAG_MUX_S0")
		)
		(pad "2" smd circle
			(at 0.40005 0 180)
			(size 0 0)
			(layers "F.Cu" "F.Mask" "F.Paste")
			(net "GND")
		)
	)
	(footprint ""
		(layer "F.Cu")
		(at 334.731614 -144.055592 180)
		(property "Reference" "PC237"
			(at 0 0 180)
			(layer "F.SilkS")
			(hide yes)
			(effects
				(font
					(size 1.27 1.27)
				)
			)
		)
		(property "Value" ""
			(at 0 0 180)
			(layer "F.Fab")
			(effects
				(font
					(size 1.27 1.27)
				)
			)
		)
		(duplicate_pad_numbers_are_jumpers no)
		(fp_line
			(start 0.7874 0.4064)
			(end -0.7874 0.4064)
			(stroke
				(width 0.1524)
				(type default)
			)
			(layer "F.SilkS")
		)
		(fp_line
			(start 0.7874 -0.4064)
			(end 0.7874 0.4064)
			(stroke
				(width 0.1524)
				(type default)
			)
			(layer "F.SilkS")
		)
		(fp_line
			(start -0.7874 0.4064)
			(end -0.7874 -0.4064)
			(stroke
				(width 0.1524)
				(type default)
			)
			(layer "F.SilkS")
		)
		(fp_line
			(start -0.7874 -0.4064)
			(end 0.7874 -0.4064)
			(stroke
				(width 0.1524)
				(type default)
			)
			(layer "F.SilkS")
		)
		(fp_line
			(start 0.67945 0.3048)
			(end 0.120396 0.3048)
			(stroke
				(width 0.1)
				(type default)
			)
			(layer "F.Fab")
		)
		(fp_line
			(start 0.67945 -0.3048)
			(end 0.67945 0.3048)
			(stroke
				(width 0.1)
				(type default)
			)
			(layer "F.Fab")
		)
		(fp_line
			(start 0.12065 -0.2794)
			(end 0.12065 -0.3048)
			(stroke
				(width 0.1)
				(type default)
			)
			(layer "F.Fab")
		)
		(fp_line
			(start 0.12065 -0.3048)
			(end 0.67945 -0.3048)
			(stroke
				(width 0.1)
				(type default)
			)
			(layer "F.Fab")
		)
		(fp_line
			(start 0.120396 0.3048)
			(end 0.120396 0.2794)
			(stroke
				(width 0.1)
				(type default)
			)
			(layer "F.Fab")
		)
		(fp_line
			(start 0.120396 0.2794)
			(end -0.12065 0.2794)
			(stroke
				(width 0.1)
				(type default)
			)
			(layer "F.Fab")
		)
		(fp_line
			(start -0.12065 0.3048)
			(end -0.67945 0.3048)
			(stroke
				(width 0.1)
				(type default)
			)
			(layer "F.Fab")
		)
		(fp_line
			(start -0.12065 0.2794)
			(end -0.12065 0.3048)
			(stroke
				(width 0.1)
				(type default)
			)
			(layer "F.Fab")
		)
		(fp_line
			(start -0.12065 -0.2794)
			(end 0.12065 -0.2794)
			(stroke
				(width 0.1)
				(type default)
			)
			(layer "F.Fab")
		)
		(fp_line
			(start -0.12065 -0.305054)
			(end -0.12065 -0.2794)
			(stroke
				(width 0.1)
				(type default)
			)
			(layer "F.Fab")
		)
		(fp_line
			(start -0.67945 0.3048)
			(end -0.67945 -0.305054)
			(stroke
				(width 0.1)
				(type default)
			)
			(layer "F.Fab")
		)
		(fp_line
			(start -0.67945 -0.305054)
			(end -0.12065 -0.305054)
			(stroke
				(width 0.1)
				(type default)
			)
			(layer "F.Fab")
		)
		(pad "1" smd circle
			(at -0.40005 0 180)
			(size 0 0)
			(layers "F.Cu" "F.Mask" "F.Paste")
			(net "SW_P12V_AUX_PVDD18_S5_P0_FLT")
		)
		(pad "2" smd circle
			(at 0.40005 0 180)
			(size 0 0)
			(layers "F.Cu" "F.Mask" "F.Paste")
			(net "GND")
		)
	)
)
